# BASEBOARD_FAB2 (Tioga Pass) — schematic netlist excerpt (pin names and nets, part order shuffled) for the footprints in the layout excerpt that follows; sources: Cadence DE-HDL packaged netlist, KiCad conversion of Wiwynn_Tioga_Pass_MB.brd

J4B1  SCONN288_H44441004  SCONN  pkg PIP  page 49
  \12v\(1)  = P12V_NVDIMM_DEF
  VSS(93)  = GND
  DQ(4)  = M_D_DQ<5>
  VSS(92)  = GND
  DQ(0)  = M_D_DQ<1>
  VSS(91)  = GND
  DQS9P  = M_D_DQS_DP<9>
  DQS9N  = M_D_DQS_DN<9>
  VSS(90)  = GND
  DQ(6)  = M_D_DQ<7>
  VSS(89)  = GND
  DQ(2)  = M_D_DQ<3>
  VSS(88)  = GND
  DQ(12)  = M_D_DQ<13>
  VSS(87)  = GND
  DQ(8)  = M_D_DQ<9>
  VSS(86)  = GND
  DQS10P  = M_D_DQS_DP<10>
  DQS10N  = M_D_DQS_DN<10>
  VSS(85)  = GND
  DQ(14)  = M_D_DQ<15>
  VSS(84)  = GND
  DQ(10)  = M_D_DQ<11>
  VSS(83)  = GND
  DQ(20)  = M_D_DQ<21>
  VSS(82)  = GND
  DQ(16)  = M_D_DQ<17>
  VSS(81)  = GND
  DQS11P  = M_D_DQS_DP<11>
  DQS11N  = M_D_DQS_DN<11>
  VSS(80)  = GND
  DQ(22)  = M_D_DQ<23>
  VSS(79)  = GND
  DQ(18)  = M_D_DQ<19>
  VSS(78)  = GND
  DQ(28)  = M_D_DQ<29>
  VSS(77)  = GND
  DQ(24)  = M_D_DQ<25>
  VSS(76)  = GND
  DQS12P  = M_D_DQS_DP<12>
  DQS12N  = M_D_DQS_DN<12>
  VSS(75)  = GND
  DQ(30)  = M_D_DQ<31>
  VSS(74)  = GND
  DQ(26)  = M_D_DQ<27>
  VSS(73)  = GND
  CB(4)  = M_D_ECC<5>
  VSS(72)  = GND
  CB(0)  = M_D_ECC<1>
  VSS(71)  = GND
  DQS17P  = M_D_DQS_DP<17>
  DQS17N  = M_D_DQS_DN<17>
  VSS(70)  = GND
  CB(6)  = M_D_ECC<7>
  VSS(69)  = GND
  CB(2)  = M_D_ECC<3>
  VSS(68)  = GND
  RESET_N  = M_DEF_RST_N
  VDD(25)  = PVDDQ_DEF
  CKE(0)  = M_D_CKE<0>
  VDD(24)  = PVDDQ_DEF
  ACT_N  = M_D_ACT_N
  BG(0)  = M_D_BG<0>
  VDD(23)  = PVDDQ_DEF
  A12  = M_D_MA<12>
  A9  = M_D_MA<9>
  VDD(22)  = PVDDQ_DEF
  A8  = M_D_MA<8>
  A6  = M_D_MA<6>
  VDD(21)  = PVDDQ_DEF
  A3  = M_D_MA<3>
  A1  = M_D_MA<1>
  VDD(20)  = PVDDQ_DEF
  CK0P  = M_D_CLK_DP<0>
  CK0N  = M_D_CLK_DN<0>
  VDD(19)  = PVDDQ_DEF
  VTT(1)  = PVTT_DEF
  EVENT_N  = FM_DIMM_EVENT_COD_N
  A0  = M_D_MA<0>
  VDD(18)  = PVDDQ_DEF
  BA(0)  = M_D_BA<0>
  A16_RAS_N  = M_D_MA<16>
  VDD(17)  = PVDDQ_DEF
  S0_N  = M_D_CS_N<0>
  VDD(16)  = PVDDQ_DEF
  A15_CAS_N  = M_D_MA<15>
  ODT(0)  = M_D_ODT<0>
  VDD(15)  = PVDDQ_DEF
  S1_N  = M_D_CS_N<1>
  VDD(14)  = PVDDQ_DEF
  ODT(1)  = M_D_ODT<1>
  VDD(13)  = PVDDQ_DEF
  S2_N_C(0)  = M_D_CS_N<2>
  VSS(67)  = GND
  DQ(36)  = M_D_DQ<37>
  VSS(66)  = GND
  DQ(32)  = M_D_DQ<33>
  VSS(65)  = GND
  DQS13P  = M_D_DQS_DP<13>
  DQS13N  = M_D_DQS_DN<13>
  VSS(64)  = GND
  DQ(38)  = M_D_DQ<39>
  VSS(63)  = GND
  DQ(34)  = M_D_DQ<35>
  VSS(62)  = GND
  DQ(44)  = M_D_DQ<45>
  VSS(61)  = GND
  DQ(40)  = M_D_DQ<41>
  VSS(60)  = GND
  DQS14P  = M_D_DQS_DP<14>
  DQS14N  = M_D_DQS_DN<14>
  VSS(59)  = GND
  DQ(46)  = M_D_DQ<47>
  VSS(58)  = GND
  DQ(42)  = M_D_DQ<43>
  VSS(57)  = GND
  DQ(52)  = M_D_DQ<53>
  VSS(56)  = GND
  DQ(48)  = M_D_DQ<49>
  VSS(55)  = GND
  DQS15P  = M_D_DQS_DP<15>
  DQS15N  = M_D_DQS_DN<15>
  VSS(54)  = GND
  DQ(54)  = M_D_DQ<55>
  VSS(53)  = GND
  DQ(50)  = M_D_DQ<51>
  VSS(52)  = GND
  DQ(60)  = M_D_DQ<61>
  VSS(51)  = GND
  DQ(56)  = M_D_DQ<57>
  VSS(50)  = GND
  DQS16P  = M_D_DQS_DP<16>
  DQS16N  = M_D_DQS_DN<16>
  VSS(49)  = GND
  DQ(62)  = M_D_DQ<63>
  VSS(48)  = GND
  DQ(58)  = M_D_DQ<59>
  VSS(47)  = GND
  SA(0)  = GND
  SA(1)  = GND
  SCL  = SMB_DDR_DEF_VPP_SCL
  VPP(4)  = PVPP_DEF
  VPP(3)  = PVPP_DEF
  RFU(2)  = TP_CH_D_DIMM_D0_RFU_2
  \12v\(0)  = P12V_NVDIMM_DEF
  VREFCA  = M_D_VREF
  VSS(46)  = GND
  DQ(5)  = M_D_DQ<4>
  VSS(45)  = GND
  DQ(1)  = M_D_DQ<0>
  VSS(44)  = GND
  DQS0N  = M_D_DQS_DN<0>
  DQS0P  = M_D_DQS_DP<0>
  VSS(43)  = GND
  DQ(7)  = M_D_DQ<6>
  VSS(42)  = GND
  DQ(3)  = M_D_DQ<2>
  VSS(41)  = GND
  DQ(13)  = M_D_DQ<12>
  VSS(40)  = GND
  DQ(9)  = M_D_DQ<8>
  VSS(39)  = GND
  DQS1N  = M_D_DQS_DN<1>
  DQS1P  = M_D_DQS_DP<1>
  VSS(38)  = GND
  DQ(15)  = M_D_DQ<14>
  VSS(37)  = GND
  DQ(11)  = M_D_DQ<10>
  VSS(36)  = GND
  DQ(21)  = M_D_DQ<20>
  VSS(35)  = GND
  DQ(17)  = M_D_DQ<16>
  VSS(34)  = GND
  DQS2N  = M_D_DQS_DN<2>
  DQS2P  = M_D_DQS_DP<2>
  VSS(33)  = GND
  DQ(23)  = M_D_DQ<22>
  VSS(32)  = GND
  DQ(19)  = M_D_DQ<18>
  VSS(31)  = GND
  DQ(29)  = M_D_DQ<28>
  VSS(30)  = GND
  DQ(25)  = M_D_DQ<24>
  VSS(29)  = GND
  DQS3N  = M_D_DQS_DN<3>
  DQS3P  = M_D_DQS_DP<3>
  VSS(28)  = GND
  DQ(31)  = M_D_DQ<30>
  VSS(27)  = GND
  DQ(27)  = M_D_DQ<26>
  VSS(26)  = GND
  CB(5)  = M_D_ECC<4>
  VSS(25)  = GND
  CB(1)  = M_D_ECC<0>
  VSS(24)  = GND
  DQS8N  = M_D_DQS_DN<8>
  DQS8P  = M_D_DQS_DP<8>
  VSS(23)  = GND
  CB(7)  = M_D_ECC<6>
  VSS(22)  = GND
  CB(3)  = M_D_ECC<2>
  VSS(21)  = GND
  CKE(1)  = M_D_CKE<1>
  VDD(12)  = PVDDQ_DEF
  RFU(0)  = TP_CH_D_DIMM_D0_RFU_0
  VDD(11)  = PVDDQ_DEF
  BG(1)  = M_D_BG<1>
  ALERT_N  = M_D_ALERT_N
  VDD(10)  = PVDDQ_DEF
  A11  = M_D_MA<11>
  A7  = M_D_MA<7>
  VDD(9)  = PVDDQ_DEF
  A5  = M_D_MA<5>
  A4  = M_D_MA<4>
  VDD(8)  = PVDDQ_DEF
  A2  = M_D_MA<2>
  VDD(7)  = PVDDQ_DEF
  CK1P  = M_D_CLK_DP<1>
  CK1N  = M_D_CLK_DN<1>
  VDD(6)  = PVDDQ_DEF
  VTT(0)  = PVTT_DEF
  PAR  = M_D_PAR
  VDD(5)  = PVDDQ_DEF
  BA(1)  = M_D_BA<1>
  A10  = M_D_MA<10>
  VDD(4)  = PVDDQ_DEF
  RFU(1)  = TP_CH_D_DIMM_D0_RFU_1
  A14_WE_N  = M_D_MA<14>
  VDD(3)  = PVDDQ_DEF
  SAVE_N_NC  = FM_ADR_COMPLETE_DEF_N
  VDD(2)  = PVDDQ_DEF
  A13  = M_D_MA<13>
  VDD(1)  = PVDDQ_DEF
  A17  = M_D_MA<17>
  C(2)  = M_D_C<2>
  VDD(0)  = PVDDQ_DEF
  S3_N_C(1)  = M_D_CS_N<3>
  SA(2)  = GND
  VSS(20)  = GND
  DQ(37)  = M_D_DQ<36>
  VSS(19)  = GND
  DQ(33)  = M_D_DQ<32>
  VSS(18)  = GND
  DQS4N  = M_D_DQS_DN<4>
  DQS4P  = M_D_DQS_DP<4>
  VSS(17)  = GND
  DQ(39)  = M_D_DQ<38>
  VSS(16)  = GND
  DQ(35)  = M_D_DQ<34>
  VSS(15)  = GND
  DQ(45)  = M_D_DQ<44>
  VSS(14)  = GND
  DQ(41)  = M_D_DQ<40>
  VSS(13)  = GND
  DQS5N  = M_D_DQS_DN<5>
  DQS5P  = M_D_DQS_DP<5>
  VSS(12)  = GND
  DQ(47)  = M_D_DQ<46>
  VSS(11)  = GND
  DQ(43)  = M_D_DQ<42>
  VSS(10)  = GND
  DQ(53)  = M_D_DQ<52>
  VSS(9)  = GND
  DQ(49)  = M_D_DQ<48>
  VSS(8)  = GND
  DQS6N  = M_D_DQS_DN<6>
  DQS6P  = M_D_DQS_DP<6>
  VSS(7)  = GND
  DQ(55)  = M_D_DQ<54>
  VSS(6)  = GND
  DQ(51)  = M_D_DQ<50>
  VSS(5)  = GND
  DQ(61)  = M_D_DQ<60>
  VSS(4)  = GND
  DQ(57)  = M_D_DQ<56>
  VSS(3)  = GND
  DQS7N  = M_D_DQS_DN<7>
  DQS7P  = M_D_DQS_DP<7>
  VSS(2)  = GND
  DQ(63)  = M_D_DQ<62>
  VSS(1)  = GND
  DQ(59)  = M_D_DQ<58>
  VSS(0)  = GND
  VDDSPD  = PVPP_DEF
  SDA  = SMB_DDR_DEF_VPP_SDA
  VPP(1)  = PVPP_DEF
  VPP(0)  = PVPP_DEF
  VPP(2)  = PVPP_DEF

(kicad_pcb
	(version 20260206)
	(generator "pcbnew")
	(generator_version "10.0")
	(general
		(thickness 1.6)
		(legacy_teardrops no)
	)
	(paper "A4")
	(title_block
		(title "Wiwynn_Tioga_Pass_MB.brd")
		(comment 1 "Tioga Pass / footprint 990 of 4770 (J4B1), pads 153-202 of 291")
	)
	(layers
		(0 "F.Cu" signal "TOP")
		(4 "In1.Cu" signal "L2GND")
		(6 "In2.Cu" signal "L3")
		(8 "In3.Cu" signal "L4GND")
		(10 "In4.Cu" signal "L5")
		(12 "In5.Cu" signal "L6GND")
		(14 "In6.Cu" signal "L7VCC")
		(16 "In7.Cu" signal "L8VCC")
		(18 "In8.Cu" signal "L9GND")
		(20 "In9.Cu" signal "L10")
		(22 "In10.Cu" signal "L11GND")
		(24 "In11.Cu" signal "L12")
		(26 "In12.Cu" signal "L13GND")
		(2 "B.Cu" signal "BOTTOM")
		(9 "F.Adhes" user "F.Adhesive")
		(11 "B.Adhes" user "B.Adhesive")
		(13 "F.Paste" user "Package Geometry/Pastemask Top")
		(15 "B.Paste" user "Package Geometry/Pastemask Bottom")
		(5 "F.SilkS" user "Ref Des/Silkscreen Top")
		(7 "B.SilkS" user "Ref Des/Silkscreen Bottom")
		(1 "F.Mask" user "Board Geometry/Soldermask Top")
		(3 "B.Mask" user "Board Geometry/Soldermask Bottom")
		(17 "Dwgs.User" user "User.Drawings")
		(19 "Cmts.User" user "User.Comments")
		(21 "Eco1.User" user "User.Eco1")
		(23 "Eco2.User" user "User.Eco2")
		(25 "Edge.Cuts" user "Board Geometry/Outline")
		(27 "Margin" user)
		(31 "F.CrtYd" user "Package Geometry/Place Bound Top")
		(29 "B.CrtYd" user "Package Geometry/Place Bound Bottom")
		(35 "F.Fab" user "Ref Des/Assembly Top")
		(33 "B.Fab" user "Ref Des/Assembly Bottom")
	)
	(footprint ""
		(layer "F.Cu")
		(at 194.700398 -133.0706 90)
		(property "Reference" "J4B1"
			(at -5.087112 42.28211 0)
			(unlocked yes)
			(layer "F.SilkS")
			(effects
				(font
					(size 0.7874 0.5842)
					(thickness 0.1524)
				)
				(justify left)
			)
		)
		(property "Value" ""
			(at 0 0 90)
			(layer "F.Fab")
			(effects
				(font
					(size 1.27 1.27)
				)
			)
		)
		(duplicate_pad_numbers_are_jumpers no)
		(pad "150" smd rect
			(at 4.59994 4.249928 90)
			(size 1.8034 0.508)
			(layers "F.Cu" "F.Mask" "F.Paste")
			(net "M_D_DQ<0>")
		)
		(pad "151" smd rect
			(at 4.59994 5.100066 90)
			(size 1.8034 0.508)
			(layers "F.Cu" "F.Mask" "F.Paste")
			(net "GND")
		)
		(pad "152" smd rect
			(at 4.59994 5.94995 90)
			(size 1.8034 0.508)
			(layers "F.Cu" "F.Mask" "F.Paste")
			(net "M_D_DQS_DN<0>")
		)
		(pad "153" smd rect
			(at 4.59994 6.800088 90)
			(size 1.8034 0.508)
			(layers "F.Cu" "F.Mask" "F.Paste")
			(net "M_D_DQS_DP<0>")
		)
		(pad "154" smd rect
			(at 4.59994 7.649972 90)
			(size 1.8034 0.508)
			(layers "F.Cu" "F.Mask" "F.Paste")
			(net "GND")
		)
		(pad "155" smd rect
			(at 4.59994 8.50011 90)
			(size 1.8034 0.508)
			(layers "F.Cu" "F.Mask" "F.Paste")
			(net "M_D_DQ<6>")
		)
		(pad "156" smd rect
			(at 4.59994 9.349994 90)
			(size 1.8034 0.508)
			(layers "F.Cu" "F.Mask" "F.Paste")
			(net "GND")
		)
		(pad "157" smd rect
			(at 4.59994 10.199878 90)
			(size 1.8034 0.508)
			(layers "F.Cu" "F.Mask" "F.Paste")
			(net "M_D_DQ<2>")
		)
		(pad "158" smd rect
			(at 4.59994 11.050016 90)
			(size 1.8034 0.508)
			(layers "F.Cu" "F.Mask" "F.Paste")
			(net "GND")
		)
		(pad "159" smd rect
			(at 4.59994 11.8999 90)
			(size 1.8034 0.508)
			(layers "F.Cu" "F.Mask" "F.Paste")
			(net "M_D_DQ<12>")
		)
		(pad "160" smd rect
			(at 4.59994 12.750038 90)
			(size 1.8034 0.508)
			(layers "F.Cu" "F.Mask" "F.Paste")
			(net "GND")
		)
		(pad "161" smd rect
			(at 4.59994 13.599922 90)
			(size 1.8034 0.508)
			(layers "F.Cu" "F.Mask" "F.Paste")
			(net "M_D_DQ<8>")
		)
		(pad "162" smd rect
			(at 4.59994 14.45006 90)
			(size 1.8034 0.508)
			(layers "F.Cu" "F.Mask" "F.Paste")
			(net "GND")
		)
		(pad "163" smd rect
			(at 4.59994 15.299944 90)
			(size 1.8034 0.508)
			(layers "F.Cu" "F.Mask" "F.Paste")
			(net "M_D_DQS_DN<1>")
		)
		(pad "164" smd rect
			(at 4.59994 16.150082 90)
			(size 1.8034 0.508)
			(layers "F.Cu" "F.Mask" "F.Paste")
			(net "M_D_DQS_DP<1>")
		)
		(pad "165" smd rect
			(at 4.59994 16.999966 90)
			(size 1.8034 0.508)
			(layers "F.Cu" "F.Mask" "F.Paste")
			(net "GND")
		)
		(pad "166" smd rect
			(at 4.59994 17.850104 90)
			(size 1.8034 0.508)
			(layers "F.Cu" "F.Mask" "F.Paste")
			(net "M_D_DQ<14>")
		)
		(pad "167" smd rect
			(at 4.59994 18.699988 90)
			(size 1.8034 0.508)
			(layers "F.Cu" "F.Mask" "F.Paste")
			(net "GND")
		)
		(pad "168" smd rect
			(at 4.59994 19.550126 90)
			(size 1.8034 0.508)
			(layers "F.Cu" "F.Mask" "F.Paste")
			(net "M_D_DQ<10>")
		)
		(pad "169" smd rect
			(at 4.59994 20.40001 90)
			(size 1.8034 0.508)
			(layers "F.Cu" "F.Mask" "F.Paste")
			(net "GND")
		)
		(pad "170" smd rect
			(at 4.59994 21.249894 90)
			(size 1.8034 0.508)
			(layers "F.Cu" "F.Mask" "F.Paste")
			(net "M_D_DQ<20>")
		)
		(pad "171" smd rect
			(at 4.59994 22.100032 90)
			(size 1.8034 0.508)
			(layers "F.Cu" "F.Mask" "F.Paste")
			(net "GND")
		)
		(pad "172" smd rect
			(at 4.59994 22.949916 90)
			(size 1.8034 0.508)
			(layers "F.Cu" "F.Mask" "F.Paste")
			(net "M_D_DQ<16>")
		)
		(pad "173" smd rect
			(at 4.59994 23.800054 90)
			(size 1.8034 0.508)
			(layers "F.Cu" "F.Mask" "F.Paste")
			(net "GND")
		)
		(pad "174" smd rect
			(at 4.59994 24.649938 90)
			(size 1.8034 0.508)
			(layers "F.Cu" "F.Mask" "F.Paste")
			(net "M_D_DQS_DN<2>")
		)
		(pad "175" smd rect
			(at 4.59994 25.500076 90)
			(size 1.8034 0.508)
			(layers "F.Cu" "F.Mask" "F.Paste")
			(net "M_D_DQS_DP<2>")
		)
		(pad "176" smd rect
			(at 4.59994 26.34996 90)
			(size 1.8034 0.508)
			(layers "F.Cu" "F.Mask" "F.Paste")
			(net "GND")
		)
		(pad "177" smd rect
			(at 4.59994 27.200098 90)
			(size 1.8034 0.508)
			(layers "F.Cu" "F.Mask" "F.Paste")
			(net "M_D_DQ<22>")
		)
		(pad "178" smd rect
			(at 4.59994 28.049982 90)
			(size 1.8034 0.508)
			(layers "F.Cu" "F.Mask" "F.Paste")
			(net "GND")
		)
		(pad "179" smd rect
			(at 4.59994 28.90012 90)
			(size 1.8034 0.508)
			(layers "F.Cu" "F.Mask" "F.Paste")
			(net "M_D_DQ<18>")
		)
		(pad "180" smd rect
			(at 4.59994 29.750004 90)
			(size 1.8034 0.508)
			(layers "F.Cu" "F.Mask" "F.Paste")
			(net "GND")
		)
		(pad "181" smd rect
			(at 4.59994 30.599888 90)
			(size 1.8034 0.508)
			(layers "F.Cu" "F.Mask" "F.Paste")
			(net "M_D_DQ<28>")
		)
		(pad "182" smd rect
			(at 4.59994 31.450026 90)
			(size 1.8034 0.508)
			(layers "F.Cu" "F.Mask" "F.Paste")
			(net "GND")
		)
		(pad "183" smd rect
			(at 4.59994 32.29991 90)
			(size 1.8034 0.508)
			(layers "F.Cu" "F.Mask" "F.Paste")
			(net "M_D_DQ<24>")
		)
		(pad "184" smd rect
			(at 4.59994 33.150048 90)
			(size 1.8034 0.508)
			(layers "F.Cu" "F.Mask" "F.Paste")
			(net "GND")
		)
		(pad "185" smd rect
			(at 4.59994 33.999932 90)
			(size 1.8034 0.508)
			(layers "F.Cu" "F.Mask" "F.Paste")
			(net "M_D_DQS_DN<3>")
		)
		(pad "186" smd rect
			(at 4.59994 34.85007 90)
			(size 1.8034 0.508)
			(layers "F.Cu" "F.Mask" "F.Paste")
			(net "M_D_DQS_DP<3>")
		)
		(pad "187" smd rect
			(at 4.59994 35.699954 90)
			(size 1.8034 0.508)
			(layers "F.Cu" "F.Mask" "F.Paste")
			(net "GND")
		)
		(pad "188" smd rect
			(at 4.59994 36.550092 90)
			(size 1.8034 0.508)
			(layers "F.Cu" "F.Mask" "F.Paste")
			(net "M_D_DQ<30>")
		)
		(pad "189" smd rect
			(at 4.59994 37.399976 90)
			(size 1.8034 0.508)
			(layers "F.Cu" "F.Mask" "F.Paste")
			(net "GND")
		)
		(pad "190" smd rect
			(at 4.59994 38.250114 90)
			(size 1.8034 0.508)
			(layers "F.Cu" "F.Mask" "F.Paste")
			(net "M_D_DQ<26>")
		)
		(pad "191" smd rect
			(at 4.59994 39.099998 90)
			(size 1.8034 0.508)
			(layers "F.Cu" "F.Mask" "F.Paste")
			(net "GND")
		)
		(pad "192" smd rect
			(at 4.59994 39.949882 90)
			(size 1.8034 0.508)
			(layers "F.Cu" "F.Mask" "F.Paste")
			(net "M_D_ECC<4>")
		)
		(pad "193" smd rect
			(at 4.59994 40.80002 90)
			(size 1.8034 0.508)
			(layers "F.Cu" "F.Mask" "F.Paste")
			(net "GND")
		)
		(pad "194" smd rect
			(at 4.59994 41.649904 90)
			(size 1.8034 0.508)
			(layers "F.Cu" "F.Mask" "F.Paste")
			(net "M_D_ECC<0>")
		)
		(pad "195" smd rect
			(at 4.59994 42.500042 90)
			(size 1.8034 0.508)
			(layers "F.Cu" "F.Mask" "F.Paste")
			(net "GND")
		)
		(pad "196" smd rect
			(at 4.59994 43.349926 90)
			(size 1.8034 0.508)
			(layers "F.Cu" "F.Mask" "F.Paste")
			(net "M_D_DQS_DN<8>")
		)
		(pad "197" smd rect
			(at 4.59994 44.200064 90)
			(size 1.8034 0.508)
			(layers "F.Cu" "F.Mask" "F.Paste")
			(net "M_D_DQS_DP<8>")
		)
		(pad "198" smd rect
			(at 4.59994 45.049948 90)
			(size 1.8034 0.508)
			(layers "F.Cu" "F.Mask" "F.Paste")
			(net "GND")
		)
		(pad "199" smd rect
			(at 4.59994 45.900086 90)
			(size 1.8034 0.508)
			(layers "F.Cu" "F.Mask" "F.Paste")
			(net "M_D_ECC<6>")
		)
	)
)
